(kicad_pcb
	(version 20260206)
	(generator "pcbnew")
	(generator_version "10.0")
	(general
		(thickness 1.6)
		(legacy_teardrops no)
	)
	(paper "A4")
	(title_block
		(title "baseboard — 13948-1b.1110WZS1818.brd")
		(comment 1 "Honey Badger (Wiwynn) / footprints 528-534 of 2523")
	)
	(layers
		(0 "F.Cu" signal "TOP")
		(4 "In1.Cu" signal "L2GND")
		(6 "In2.Cu" signal "L3")
		(8 "In3.Cu" signal "L4VCC")
		(10 "In4.Cu" signal "L5VCC")
		(12 "In5.Cu" signal "L6")
		(14 "In6.Cu" signal "L7GND")
		(2 "B.Cu" signal "BOTTOM")
		(9 "F.Adhes" user "F.Adhesive")
		(11 "B.Adhes" user "B.Adhesive")
		(13 "F.Paste" user "Package Geometry/Pastemask Top")
		(15 "B.Paste" user "Package Geometry/Pastemask Bottom")
		(5 "F.SilkS" user "Ref Des/Silkscreen Top")
		(7 "B.SilkS" user "Ref Des/Silkscreen Bottom")
		(1 "F.Mask" user "Board Geometry/Soldermask Top")
		(3 "B.Mask" user "Board Geometry/Soldermask Bottom")
		(17 "Dwgs.User" user "User.Drawings")
		(19 "Cmts.User" user "User.Comments")
		(21 "Eco1.User" user "User.Eco1")
		(23 "Eco2.User" user "User.Eco2")
		(25 "Edge.Cuts" user "Board Geometry/Outline")
		(27 "Margin" user)
		(31 "F.CrtYd" user "Package Geometry/Place Bound Top")
		(29 "B.CrtYd" user "Package Geometry/Place Bound Bottom")
		(35 "F.Fab" user "Ref Des/Assembly Top")
		(33 "B.Fab" user "Ref Des/Assembly Bottom")
	)
	(footprint ""
		(layer "F.Cu")
		(at 112.23117 -71.0946 90)
		(property "Reference" "U136"
			(at 0 0 90)
			(layer "F.SilkS")
			(hide yes)
			(effects
				(font
					(size 1.27 1.27)
				)
			)
		)
		(property "Value" "TMP75AIDGKR-GP"
			(at -0.1143 -9.1948 90)
			(unlocked yes)
			(layer "F.Fab")
			(hide yes)
			(effects
				(font
					(size 1.016 1.016)
					(thickness 0.1524)
				)
			)
		)
		(property "Device Type" "MSOP8-1H44"
			(at -0.1143 -10.795 90)
			(unlocked yes)
			(layer "F.Fab")
			(hide yes)
			(effects
				(font
					(size 1.016 1.016)
					(thickness 0.1524)
				)
			)
		)
		(duplicate_pad_numbers_are_jumpers no)
		(fp_line
			(start 1.0795 -1.016)
			(end -1.9558 -1.016)
			(stroke
				(width 0.1524)
				(type default)
			)
			(layer "F.SilkS")
		)
		(fp_line
			(start -1.9558 -1.016)
			(end -1.9558 1.016)
			(stroke
				(width 0.1524)
				(type default)
			)
			(layer "F.SilkS")
		)
		(fp_line
			(start -1.9558 -0.5461)
			(end -1.4478 -0.0381)
			(stroke
				(width 0.1524)
				(type default)
			)
			(layer "F.SilkS")
		)
		(fp_line
			(start -1.4478 -0.0381)
			(end -1.9558 0.4699)
			(stroke
				(width 0.1524)
				(type default)
			)
			(layer "F.SilkS")
		)
		(fp_line
			(start 1.0795 1.016)
			(end 1.0795 -1.016)
			(stroke
				(width 0.1524)
				(type default)
			)
			(layer "F.SilkS")
		)
		(fp_line
			(start -1.9558 1.016)
			(end 1.0795 1.016)
			(stroke
				(width 0.1524)
				(type default)
			)
			(layer "F.SilkS")
		)
		(fp_line
			(start -1.778 1.0922)
			(end -1.778 3.048)
			(stroke
				(width 0.508)
				(type default)
			)
			(layer "F.SilkS")
		)
		(fp_poly
			(pts
				(xy -1.1557 -1.016) (xy -1.1557 1.016) (xy 1.1557 1.016) (xy 1.1557 -1.016)
			)
			(stroke
				(width 0)
				(type default)
			)
			(fill yes)
			(layer "F.SilkS")
		)
		(fp_rect
			(start -1.4986 2.4511)
			(end 1.4986 -2.4511)
			(stroke
				(width 0)
				(type default)
			)
			(fill no)
			(layer "F.CrtYd")
		)
		(fp_poly
			(pts
				(xy -2.032 3.302) (xy -2.032 -3.302) (xy 2.032 -3.302) (xy 2.032 -2.1209) (xy 1.4986 -2.1209) (xy 1.4986 -2.4511)
				(xy -1.4986 -2.4511) (xy -1.4986 2.4511) (xy 1.4986 2.4511) (xy 1.4986 -2.1082) (xy 2.032 -2.1082)
				(xy 2.032 3.302)
			)
			(stroke
				(width 0)
				(type default)
			)
			(fill no)
			(layer "F.CrtYd")
		)
		(fp_rect
			(start -2.032 3.302)
			(end 2.032 -3.302)
			(stroke
				(width 0)
				(type default)
			)
			(fill no)
			(layer "F.Fab")
		)
		(pad "1" smd rect
			(at -0.97536 2.05486 90)
			(size 0.3556 1.524)
			(layers "F.Cu" "F.Mask" "F.Paste")
			(net "TEMP_4_SDA")
		)
		(pad "2" smd rect
			(at -0.32512 2.05486 90)
			(size 0.3556 1.524)
			(layers "F.Cu" "F.Mask" "F.Paste")
			(net "TEMP_4_SCL")
		)
		(pad "3" smd rect
			(at 0.32512 2.05486 90)
			(size 0.3556 1.524)
			(layers "F.Cu" "F.Mask" "F.Paste")
			(net "TEMP_4_ALERT")
		)
		(pad "4" smd rect
			(at 0.97536 2.05486 90)
			(size 0.3556 1.524)
			(layers "F.Cu" "F.Mask" "F.Paste")
			(net "GND")
		)
		(pad "5" smd rect
			(at 0.97536 -2.05486 90)
			(size 0.3556 1.524)
			(layers "F.Cu" "F.Mask" "F.Paste")
			(net "TEMP_4_A2")
		)
		(pad "6" smd rect
			(at 0.32512 -2.05486 90)
			(size 0.3556 1.524)
			(layers "F.Cu" "F.Mask" "F.Paste")
			(net "TEMP_4_A1")
		)
		(pad "7" smd rect
			(at -0.32512 -2.05486 90)
			(size 0.3556 1.524)
			(layers "F.Cu" "F.Mask" "F.Paste")
			(net "TEMP_4_A0")
		)
		(pad "8" smd rect
			(at -0.97536 -2.05486 90)
			(size 0.3556 1.524)
			(layers "F.Cu" "F.Mask" "F.Paste")
			(net "P3V3_STBY")
		)
	)
	(footprint ""
		(layer "F.Cu")
		(at 193.737992 -31.369 90)
		(property "Reference" "BC2"
			(at 0 0 90)
			(layer "F.SilkS")
			(hide yes)
			(effects
				(font
					(size 1.27 1.27)
				)
			)
		)
		(property "Value" "SC2D2U10V3KX-1GP"
			(at 0 -2.8194 90)
			(unlocked yes)
			(layer "F.Fab")
			(hide yes)
			(effects
				(font
					(size 1.016 1.016)
					(thickness 0.1524)
				)
			)
		)
		(property "Device Type" "C603H36"
			(at 0 -4.3434 90)
			(unlocked yes)
			(layer "F.Fab")
			(hide yes)
			(effects
				(font
					(size 1.016 1.016)
					(thickness 0.1524)
				)
			)
		)
		(duplicate_pad_numbers_are_jumpers no)
		(fp_line
			(start 0.508 0)
			(end -0.508 0)
			(stroke
				(width 0.2032)
				(type default)
			)
			(layer "F.SilkS")
		)
		(fp_rect
			(start -0.5842 1.3335)
			(end 0.5842 -1.3335)
			(stroke
				(width 0)
				(type default)
			)
			(fill no)
			(layer "F.CrtYd")
		)
		(fp_rect
			(start -0.5842 1.3335)
			(end 0.5842 -1.3335)
			(stroke
				(width 0)
				(type default)
			)
			(fill no)
			(layer "F.Fab")
		)
		(pad "1" smd custom
			(at 0 -0.762 90)
			(size 0.2159 0.2159)
			(layers "F.Cu" "F.Mask" "F.Paste")
			(net "PHY_DVDD")
			(options
				(clearance outline)
				(anchor circle)
			)
			(primitives
				(gr_poly
					(pts
						(arc
							(start -0.3302 -0.4318)
							(mid -0.402042 -0.402042)
							(end -0.4318 -0.3302)
						)
						(arc
							(start -0.4318 0.3302)
							(mid -0.402042 0.402042)
							(end -0.3302 0.4318)
						)
						(arc
							(start 0.3302 0.4318)
							(mid 0.402042 0.402042)
							(end 0.4318 0.3302)
						)
						(arc
							(start 0.4318 -0.3302)
							(mid 0.402042 -0.402042)
							(end 0.3302 -0.4318)
						)
					)
					(width 0)
					(fill yes)
				)
			)
		)
		(pad "2" smd custom
			(at 0 0.762 90)
			(size 0.2159 0.2159)
			(layers "F.Cu" "F.Mask" "F.Paste")
			(net "GND")
			(options
				(clearance outline)
				(anchor circle)
			)
			(primitives
				(gr_poly
					(pts
						(arc
							(start -0.3302 -0.4318)
							(mid -0.402042 -0.402042)
							(end -0.4318 -0.3302)
						)
						(arc
							(start -0.4318 0.3302)
							(mid -0.402042 0.402042)
							(end -0.3302 0.4318)
						)
						(arc
							(start 0.3302 0.4318)
							(mid 0.402042 0.402042)
							(end 0.4318 0.3302)
						)
						(arc
							(start 0.4318 -0.3302)
							(mid 0.402042 -0.402042)
							(end 0.3302 -0.4318)
						)
					)
					(width 0)
					(fill yes)
				)
			)
		)
	)
	(footprint ""
		(layer "F.Cu")
		(at 89.662 -225.806 -90)
		(property "Reference" "SR308"
			(at 0 0 270)
			(layer "F.SilkS")
			(hide yes)
			(effects
				(font
					(size 1.27 1.27)
				)
			)
		)
		(property "Value" "0R2J-2-GP"
			(at 0.064008 -3.993896 270)
			(unlocked yes)
			(layer "F.Fab")
			(hide yes)
			(effects
				(font
					(size 1.016 1.016)
					(thickness 0.1524)
				)
			)
		)
		(property "Device Type" "R402H16"
			(at 0.064008 -5.517896 270)
			(unlocked yes)
			(layer "F.Fab")
			(hide yes)
			(effects
				(font
					(size 1.016 1.016)
					(thickness 0.1524)
				)
			)
		)
		(duplicate_pad_numbers_are_jumpers no)
		(fp_line
			(start -0.508 -0.9398)
			(end -0.508 0.9398)
			(stroke
				(width 0.1524)
				(type default)
			)
			(layer "F.SilkS")
		)
		(fp_line
			(start 0.508 -0.9398)
			(end -0.508 -0.9398)
			(stroke
				(width 0.1524)
				(type default)
			)
			(layer "F.SilkS")
		)
		(fp_rect
			(start -0.508 0.9398)
			(end 0.508 -0.9398)
			(stroke
				(width 0)
				(type default)
			)
			(fill no)
			(layer "F.CrtYd")
		)
		(fp_rect
			(start -0.508 0.9398)
			(end 0.508 -0.9398)
			(stroke
				(width 0)
				(type default)
			)
			(fill no)
			(layer "F.Fab")
		)
		(pad "1" smd custom
			(at 0 -0.4445 270)
			(size 0.1397 0.1397)
			(layers "F.Cu" "F.Mask" "F.Paste")
			(net "I2C_IO_EXP_RESET#_FLT")
			(options
				(clearance outline)
				(anchor circle)
			)
			(primitives
				(gr_poly
					(pts
						(arc
							(start -0.1778 -0.2794)
							(mid -0.249642 -0.249642)
							(end -0.2794 -0.1778)
						)
						(arc
							(start -0.2794 0.1778)
							(mid -0.249642 0.249642)
							(end -0.1778 0.2794)
						)
						(arc
							(start 0.1778 0.2794)
							(mid 0.249642 0.249642)
							(end 0.2794 0.1778)
						)
						(arc
							(start 0.2794 -0.1778)
							(mid 0.249642 -0.249642)
							(end 0.1778 -0.2794)
						)
					)
					(width 0)
					(fill yes)
				)
			)
		)
		(pad "2" smd custom
			(at 0 0.4445 270)
			(size 0.1397 0.1397)
			(layers "F.Cu" "F.Mask" "F.Paste")
			(net "HDD_LED_RESET_N")
			(options
				(clearance outline)
				(anchor circle)
			)
			(primitives
				(gr_poly
					(pts
						(arc
							(start -0.1778 -0.2794)
							(mid -0.249642 -0.249642)
							(end -0.2794 -0.1778)
						)
						(arc
							(start -0.2794 0.1778)
							(mid -0.249642 0.249642)
							(end -0.1778 0.2794)
						)
						(arc
							(start 0.1778 0.2794)
							(mid 0.249642 0.249642)
							(end 0.2794 0.1778)
						)
						(arc
							(start 0.2794 -0.1778)
							(mid 0.249642 -0.249642)
							(end 0.1778 -0.2794)
						)
					)
					(width 0)
					(fill yes)
				)
			)
		)
	)
	(footprint ""
		(layer "F.Cu")
		(at 267.589 -71.882 90)
		(property "Reference" "C258"
			(at 0 0 90)
			(layer "F.SilkS")
			(hide yes)
			(effects
				(font
					(size 1.27 1.27)
				)
			)
		)
		(property "Value" "SC1U25V3KX-GP"
			(at 0 -2.8194 90)
			(unlocked yes)
			(layer "F.Fab")
			(hide yes)
			(effects
				(font
					(size 1.016 1.016)
					(thickness 0.1524)
				)
			)
		)
		(property "Device Type" "C603H36"
			(at 0 -4.3434 90)
			(unlocked yes)
			(layer "F.Fab")
			(hide yes)
			(effects
				(font
					(size 1.016 1.016)
					(thickness 0.1524)
				)
			)
		)
		(duplicate_pad_numbers_are_jumpers no)
		(fp_line
			(start 0.508 0)
			(end -0.508 0)
			(stroke
				(width 0.2032)
				(type default)
			)
			(layer "F.SilkS")
		)
		(fp_rect
			(start -0.5842 1.3335)
			(end 0.5842 -1.3335)
			(stroke
				(width 0)
				(type default)
			)
			(fill no)
			(layer "F.CrtYd")
		)
		(fp_rect
			(start -0.5842 1.3335)
			(end 0.5842 -1.3335)
			(stroke
				(width 0)
				(type default)
			)
			(fill no)
			(layer "F.Fab")
		)
		(pad "1" smd custom
			(at 0 -0.762 90)
			(size 0.2159 0.2159)
			(layers "F.Cu" "F.Mask" "F.Paste")
			(net "P12V_MSB")
			(options
				(clearance outline)
				(anchor circle)
			)
			(primitives
				(gr_poly
					(pts
						(arc
							(start -0.3302 -0.4318)
							(mid -0.402042 -0.402042)
							(end -0.4318 -0.3302)
						)
						(arc
							(start -0.4318 0.3302)
							(mid -0.402042 0.402042)
							(end -0.3302 0.4318)
						)
						(arc
							(start 0.3302 0.4318)
							(mid 0.402042 0.402042)
							(end 0.4318 0.3302)
						)
						(arc
							(start 0.4318 -0.3302)
							(mid 0.402042 -0.402042)
							(end 0.3302 -0.4318)
						)
					)
					(width 0)
					(fill yes)
				)
			)
		)
		(pad "2" smd custom
			(at 0 0.762 90)
			(size 0.2159 0.2159)
			(layers "F.Cu" "F.Mask" "F.Paste")
			(net "GND")
			(options
				(clearance outline)
				(anchor circle)
			)
			(primitives
				(gr_poly
					(pts
						(arc
							(start -0.3302 -0.4318)
							(mid -0.402042 -0.402042)
							(end -0.4318 -0.3302)
						)
						(arc
							(start -0.4318 0.3302)
							(mid -0.402042 0.402042)
							(end -0.3302 0.4318)
						)
						(arc
							(start 0.3302 0.4318)
							(mid 0.402042 0.402042)
							(end 0.4318 0.3302)
						)
						(arc
							(start 0.4318 -0.3302)
							(mid 0.402042 -0.402042)
							(end 0.3302 -0.4318)
						)
					)
					(width 0)
					(fill yes)
				)
			)
		)
	)
	(footprint ""
		(layer "F.Cu")
		(at 35.383216 -199.06488 -90)
		(property "Reference" "R568"
			(at 0 0 270)
			(layer "F.SilkS")
			(hide yes)
			(effects
				(font
					(size 1.27 1.27)
				)
			)
		)
		(property "Value" "0R2J-2-GP"
			(at 0.064008 -3.993896 270)
			(unlocked yes)
			(layer "F.Fab")
			(hide yes)
			(effects
				(font
					(size 1.016 1.016)
					(thickness 0.1524)
				)
			)
		)
		(property "Device Type" "R402H16"
			(at 0.064008 -5.517896 270)
			(unlocked yes)
			(layer "F.Fab")
			(hide yes)
			(effects
				(font
					(size 1.016 1.016)
					(thickness 0.1524)
				)
			)
		)
		(duplicate_pad_numbers_are_jumpers no)
		(fp_line
			(start -0.508 -0.9398)
			(end -0.508 0.9398)
			(stroke
				(width 0.1524)
				(type default)
			)
			(layer "F.SilkS")
		)
		(fp_line
			(start 0.508 -0.9398)
			(end -0.508 -0.9398)
			(stroke
				(width 0.1524)
				(type default)
			)
			(layer "F.SilkS")
		)
		(fp_rect
			(start -0.508 0.9398)
			(end 0.508 -0.9398)
			(stroke
				(width 0)
				(type default)
			)
			(fill no)
			(layer "F.CrtYd")
		)
		(fp_rect
			(start -0.508 0.9398)
			(end 0.508 -0.9398)
			(stroke
				(width 0)
				(type default)
			)
			(fill no)
			(layer "F.Fab")
		)
		(pad "1" smd custom
			(at 0 -0.4445 270)
			(size 0.1397 0.1397)
			(layers "F.Cu" "F.Mask" "F.Paste")
			(net "ADC_P1V5_E")
			(options
				(clearance outline)
				(anchor circle)
			)
			(primitives
				(gr_poly
					(pts
						(arc
							(start -0.1778 -0.2794)
							(mid -0.249642 -0.249642)
							(end -0.2794 -0.1778)
						)
						(arc
							(start -0.2794 0.1778)
							(mid -0.249642 0.249642)
							(end -0.1778 0.2794)
						)
						(arc
							(start 0.1778 0.2794)
							(mid 0.249642 0.249642)
							(end 0.2794 0.1778)
						)
						(arc
							(start 0.2794 -0.1778)
							(mid 0.249642 -0.249642)
							(end 0.1778 -0.2794)
						)
					)
					(width 0)
					(fill yes)
				)
			)
		)
		(pad "2" smd custom
			(at 0 0.4445 270)
			(size 0.1397 0.1397)
			(layers "F.Cu" "F.Mask" "F.Paste")
			(net "P1V5_E_SENSE")
			(options
				(clearance outline)
				(anchor circle)
			)
			(primitives
				(gr_poly
					(pts
						(arc
							(start -0.1778 -0.2794)
							(mid -0.249642 -0.249642)
							(end -0.2794 -0.1778)
						)
						(arc
							(start -0.2794 0.1778)
							(mid -0.249642 0.249642)
							(end -0.1778 0.2794)
						)
						(arc
							(start 0.1778 0.2794)
							(mid 0.249642 0.249642)
							(end 0.2794 0.1778)
						)
						(arc
							(start 0.2794 -0.1778)
							(mid 0.249642 -0.249642)
							(end 0.1778 -0.2794)
						)
					)
					(width 0)
					(fill yes)
				)
			)
		)
	)
	(footprint ""
		(layer "F.Cu")
		(at 323.85 -172.974 90)
		(property "Reference" "R435"
			(at 0 0 90)
			(layer "F.SilkS")
			(hide yes)
			(effects
				(font
					(size 1.27 1.27)
				)
			)
		)
		(property "Value" "0R2J-2-GP"
			(at 0.064008 -3.993896 90)
			(unlocked yes)
			(layer "F.Fab")
			(hide yes)
			(effects
				(font
					(size 1.016 1.016)
					(thickness 0.1524)
				)
			)
		)
		(property "Device Type" "R402H16"
			(at 0.064008 -5.517896 90)
			(unlocked yes)
			(layer "F.Fab")
			(hide yes)
			(effects
				(font
					(size 1.016 1.016)
					(thickness 0.1524)
				)
			)
		)
		(duplicate_pad_numbers_are_jumpers no)
		(fp_line
			(start 0.508 -0.9398)
			(end -0.508 -0.9398)
			(stroke
				(width 0.1524)
				(type default)
			)
			(layer "F.SilkS")
		)
		(fp_line
			(start -0.508 -0.9398)
			(end -0.508 0.9398)
			(stroke
				(width 0.1524)
				(type default)
			)
			(layer "F.SilkS")
		)
		(fp_rect
			(start -0.508 0.9398)
			(end 0.508 -0.9398)
			(stroke
				(width 0)
				(type default)
			)
			(fill no)
			(layer "F.CrtYd")
		)
		(fp_rect
			(start -0.508 0.9398)
			(end 0.508 -0.9398)
			(stroke
				(width 0)
				(type default)
			)
			(fill no)
			(layer "F.Fab")
		)
		(pad "1" smd custom
			(at 0 -0.4445 90)
			(size 0.1397 0.1397)
			(layers "F.Cu" "F.Mask" "F.Paste")
			(net "EXP_SMART_TX")
			(options
				(clearance outline)
				(anchor circle)
			)
			(primitives
				(gr_poly
					(pts
						(arc
							(start -0.1778 -0.2794)
							(mid -0.249642 -0.249642)
							(end -0.2794 -0.1778)
						)
						(arc
							(start -0.2794 0.1778)
							(mid -0.249642 0.249642)
							(end -0.1778 0.2794)
						)
						(arc
							(start 0.1778 0.2794)
							(mid 0.249642 0.249642)
							(end 0.2794 0.1778)
						)
						(arc
							(start 0.2794 -0.1778)
							(mid 0.249642 -0.249642)
							(end 0.1778 -0.2794)
						)
					)
					(width 0)
					(fill yes)
				)
			)
		)
		(pad "2" smd custom
			(at 0 0.4445 90)
			(size 0.1397 0.1397)
			(layers "F.Cu" "F.Mask" "F.Paste")
			(net "EXP_UART_TX_R")
			(options
				(clearance outline)
				(anchor circle)
			)
			(primitives
				(gr_poly
					(pts
						(arc
							(start -0.1778 -0.2794)
							(mid -0.249642 -0.249642)
							(end -0.2794 -0.1778)
						)
						(arc
							(start -0.2794 0.1778)
							(mid -0.249642 0.249642)
							(end -0.1778 0.2794)
						)
						(arc
							(start 0.1778 0.2794)
							(mid 0.249642 0.249642)
							(end 0.2794 0.1778)
						)
						(arc
							(start 0.2794 -0.1778)
							(mid 0.249642 -0.249642)
							(end 0.1778 -0.2794)
						)
					)
					(width 0)
					(fill yes)
				)
			)
		)
	)
	(footprint ""
		(layer "F.Cu")
		(at 114.82197 -78.359)
		(property "Reference" "STP106"
			(at 0 0 0)
			(layer "F.SilkS")
			(hide yes)
			(effects
				(font
					(size 1.27 1.27)
				)
			)
		)
		(property "Value" "TPAD28"
			(at 0.0127 -1.8034 0)
			(unlocked yes)
			(layer "F.Fab")
			(hide yes)
			(effects
				(font
					(size 1.016 1.016)
					(thickness 0.1524)
				)
			)
		)
		(property "Device Type" "TPAD28"
			(at 0.0127 -3.3274 0)
			(unlocked yes)
			(layer "F.Fab")
			(hide yes)
			(effects
				(font
					(size 1.016 1.016)
					(thickness 0.1524)
				)
			)
		)
		(duplicate_pad_numbers_are_jumpers no)
		(fp_poly
			(pts
				(arc
					(start 0.3556 0)
					(mid -0.3556 0)
					(end 0.3556 0)
				)
			)
			(stroke
				(width 0)
				(type default)
			)
			(fill no)
			(layer "F.CrtYd")
		)
		(fp_poly
			(pts
				(arc
					(start 0.6096 0)
					(mid -0.6096 0)
					(end 0.6096 0)
				)
			)
			(stroke
				(width 0)
				(type default)
			)
			(fill no)
			(layer "F.Fab")
		)
		(pad "1" smd circle
			(at 0 0)
			(size 0.7112 0.7112)
			(layers "F.Cu" "F.Mask" "F.Paste")
			(net "TEST_MUX_39")
		)
	)
)
